# T6G (Grand Teton) — schematic netlist excerpt (pin names and nets, part order shuffled) for the footprints in the layout excerpt that follows; sources: Cadence DE-HDL packaged netlist, KiCad conversion of 04192023_DAF0TMB3IC0_F0TG_MB_C_brd_V02_OCP.brd

R805  Q_RES  0 5% CHIP  pkg 0201LF  page 185 : A = SMB_RT_CPU1_P1_ROM_MUX_2D_SCL ; B = SMB_RT_CPU1_P1_ROM_MUX_2D_R_SCL
C328  Q_CAP  100UF 4V 20% X6S  pkg C0805  page 334 : A = P0V9_CPU1_RT1_2A ; B = GND
C320  Q_CAP  100UF 4V 20% X6S  pkg C0805  page 334 : A = P0V9_CPU1_RT1_2A ; B = GND
C2244  Q_CAP  22UF 4V 20% X6S  pkg C0402  page 69 : A = PVDDCR_CPU1_P0 ; B = GND

(kicad_pcb
	(version 20260206)
	(generator "pcbnew")
	(generator_version "10.0")
	(general
		(thickness 1.6)
		(legacy_teardrops no)
	)
	(paper "A4")
	(title_block
		(title "04192023_DAF0TMB3IC0_F0TG_MB_C_brd_V02_OCP.brd")
		(comment 1 "Grand Teton / footprints 7637-7640 of 8354")
	)
	(layers
		(0 "F.Cu" signal "TOP")
		(4 "In1.Cu" signal "GND")
		(6 "In2.Cu" signal "IN1")
		(8 "In3.Cu" signal "GND1")
		(10 "In4.Cu" signal "IN2")
		(12 "In5.Cu" signal "GND2")
		(14 "In6.Cu" signal "IN3")
		(16 "In7.Cu" signal "GND3")
		(18 "In8.Cu" signal "VCC")
		(20 "In9.Cu" signal "VCC1")
		(22 "In10.Cu" signal "GND4")
		(24 "In11.Cu" signal "IN4")
		(26 "In12.Cu" signal "GND5")
		(28 "In13.Cu" signal "IN5")
		(30 "In14.Cu" signal "GND6")
		(32 "In15.Cu" signal "IN6")
		(34 "In16.Cu" signal "GND7")
		(2 "B.Cu" signal "BOTTOM")
		(9 "F.Adhes" user "F.Adhesive")
		(11 "B.Adhes" user "B.Adhesive")
		(13 "F.Paste" user "Package Geometry/Pastemask Top")
		(15 "B.Paste" user "Package Geometry/Pastemask Bottom")
		(5 "F.SilkS" user "Ref Des/Silkscreen Top")
		(7 "B.SilkS" user "Ref Des/Silkscreen Bottom")
		(1 "F.Mask" user "Board Geometry/Soldermask Top")
		(3 "B.Mask" user "Board Geometry/Soldermask Bottom")
		(17 "Dwgs.User" user "User.Drawings")
		(19 "Cmts.User" user "User.Comments")
		(21 "Eco1.User" user "User.Eco1")
		(23 "Eco2.User" user "User.Eco2")
		(25 "Edge.Cuts" user "Board Geometry/Outline")
		(27 "Margin" user)
		(31 "F.CrtYd" user "Package Geometry/Place Bound Top")
		(29 "B.CrtYd" user "Package Geometry/Place Bound Bottom")
		(35 "F.Fab" user "Ref Des/Assembly Top")
		(33 "B.Fab" user "Ref Des/Assembly Bottom")
	)
	(footprint ""
		(layer "B.Cu")
		(at 102.389432 -391.81405 180)
		(property "Reference" "C328"
			(at 0 0 0)
			(layer "B.SilkS")
			(hide yes)
			(effects
				(font
					(size 1.27 1.27)
				)
				(justify mirror)
			)
		)
		(property "Value" ""
			(at 0 0 0)
			(layer "B.Fab")
			(effects
				(font
					(size 1.27 1.27)
				)
				(justify mirror)
			)
		)
		(duplicate_pad_numbers_are_jumpers no)
		(fp_line
			(start 1.524 0.762)
			(end 1.524 -0.762)
			(stroke
				(width 0.1524)
				(type default)
			)
			(layer "B.SilkS")
		)
		(fp_line
			(start 1.524 -0.762)
			(end -1.524 -0.762)
			(stroke
				(width 0.1524)
				(type default)
			)
			(layer "B.SilkS")
		)
		(fp_line
			(start -1.524 0.762)
			(end 1.524 0.762)
			(stroke
				(width 0.1524)
				(type default)
			)
			(layer "B.SilkS")
		)
		(fp_line
			(start -1.524 -0.762)
			(end -1.524 0.762)
			(stroke
				(width 0.1524)
				(type default)
			)
			(layer "B.SilkS")
		)
		(fp_line
			(start 1.1049 0.724916)
			(end -1.1049 0.724916)
			(stroke
				(width 0.1)
				(type default)
			)
			(layer "B.Fab")
		)
		(fp_line
			(start 1.1049 -0.724916)
			(end 1.1049 0.724916)
			(stroke
				(width 0.1)
				(type default)
			)
			(layer "B.Fab")
		)
		(fp_line
			(start -1.1049 0.724916)
			(end -1.1049 -0.724916)
			(stroke
				(width 0.1)
				(type default)
			)
			(layer "B.Fab")
		)
		(fp_line
			(start -1.1049 -0.724916)
			(end 1.1049 -0.724916)
			(stroke
				(width 0.1)
				(type default)
			)
			(layer "B.Fab")
		)
		(pad "1" smd rect
			(at 0.889 0 180)
			(size 1.016 1.27)
			(layers "B.Cu" "B.Mask" "B.Paste")
			(net "P0V9_CPU1_RT1_2A")
		)
		(pad "2" smd rect
			(at -0.889 0 180)
			(size 1.016 1.27)
			(layers "B.Cu" "B.Mask" "B.Paste")
			(net "GND")
		)
	)
	(footprint ""
		(layer "B.Cu")
		(at 238.633 -337.312 180)
		(property "Reference" "R805"
			(at 0 0 0)
			(layer "B.SilkS")
			(hide yes)
			(effects
				(font
					(size 1.27 1.27)
				)
				(justify mirror)
			)
		)
		(property "Value" ""
			(at 0 0 0)
			(layer "B.Fab")
			(effects
				(font
					(size 1.27 1.27)
				)
				(justify mirror)
			)
		)
		(duplicate_pad_numbers_are_jumpers no)
		(fp_line
			(start 0.32512 0.175006)
			(end 0.32512 -0.175006)
			(stroke
				(width 0.1)
				(type default)
			)
			(layer "B.Fab")
		)
		(fp_line
			(start 0.32512 -0.175006)
			(end -0.32512 -0.175006)
			(stroke
				(width 0.1)
				(type default)
			)
			(layer "B.Fab")
		)
		(fp_line
			(start -0.32512 0.175006)
			(end 0.32512 0.175006)
			(stroke
				(width 0.1)
				(type default)
			)
			(layer "B.Fab")
		)
		(fp_line
			(start -0.32512 -0.175006)
			(end -0.32512 0.175006)
			(stroke
				(width 0.1)
				(type default)
			)
			(layer "B.Fab")
		)
		(pad "1" smd rect
			(at 0.2667 0)
			(size 0.3048 0.381)
			(layers "B.Cu" "B.Mask" "B.Paste")
			(net "SMB_RT_CPU1_P1_ROM_MUX_2D_SCL")
		)
		(pad "2" smd rect
			(at -0.2667 0 180)
			(size 0.3048 0.381)
			(layers "B.Cu" "B.Mask" "B.Paste")
			(net "SMB_RT_CPU1_P1_ROM_MUX_2D_R_SCL")
		)
	)
	(footprint ""
		(layer "B.Cu")
		(at 74.947272 -390.587484)
		(property "Reference" "C320"
			(at 0 0 0)
			(layer "B.SilkS")
			(hide yes)
			(effects
				(font
					(size 1.27 1.27)
				)
				(justify mirror)
			)
		)
		(property "Value" ""
			(at 0 0 0)
			(layer "B.Fab")
			(effects
				(font
					(size 1.27 1.27)
				)
				(justify mirror)
			)
		)
		(duplicate_pad_numbers_are_jumpers no)
		(fp_line
			(start -1.524 -0.762)
			(end -1.524 0.762)
			(stroke
				(width 0.1524)
				(type default)
			)
			(layer "B.SilkS")
		)
		(fp_line
			(start -1.524 0.762)
			(end 1.524 0.762)
			(stroke
				(width 0.1524)
				(type default)
			)
			(layer "B.SilkS")
		)
		(fp_line
			(start 1.524 -0.762)
			(end -1.524 -0.762)
			(stroke
				(width 0.1524)
				(type default)
			)
			(layer "B.SilkS")
		)
		(fp_line
			(start 1.524 0.762)
			(end 1.524 -0.762)
			(stroke
				(width 0.1524)
				(type default)
			)
			(layer "B.SilkS")
		)
		(fp_line
			(start -1.1049 -0.724916)
			(end 1.1049 -0.724916)
			(stroke
				(width 0.1)
				(type default)
			)
			(layer "B.Fab")
		)
		(fp_line
			(start -1.1049 0.724916)
			(end -1.1049 -0.724916)
			(stroke
				(width 0.1)
				(type default)
			)
			(layer "B.Fab")
		)
		(fp_line
			(start 1.1049 -0.724916)
			(end 1.1049 0.724916)
			(stroke
				(width 0.1)
				(type default)
			)
			(layer "B.Fab")
		)
		(fp_line
			(start 1.1049 0.724916)
			(end -1.1049 0.724916)
			(stroke
				(width 0.1)
				(type default)
			)
			(layer "B.Fab")
		)
		(pad "1" smd rect
			(at 0.889 0)
			(size 1.016 1.27)
			(layers "B.Cu" "B.Mask" "B.Paste")
			(net "P0V9_CPU1_RT1_2A")
		)
		(pad "2" smd rect
			(at -0.889 0)
			(size 1.016 1.27)
			(layers "B.Cu" "B.Mask" "B.Paste")
			(net "GND")
		)
	)
	(footprint ""
		(layer "B.Cu")
		(at 359.994454 -267.52931 -90)
		(property "Reference" "C2244"
			(at 0 0 90)
			(layer "B.SilkS")
			(hide yes)
			(effects
				(font
					(size 1.27 1.27)
				)
				(justify mirror)
			)
		)
		(property "Value" ""
			(at 0 0 90)
			(layer "B.Fab")
			(effects
				(font
					(size 1.27 1.27)
				)
				(justify mirror)
			)
		)
		(duplicate_pad_numbers_are_jumpers no)
		(fp_line
			(start -0.7874 0.4064)
			(end 0.7874 0.4064)
			(stroke
				(width 0.1524)
				(type default)
			)
			(layer "B.SilkS")
		)
		(fp_line
			(start 0.7874 0.4064)
			(end 0.7874 -0.4064)
			(stroke
				(width 0.1524)
				(type default)
			)
			(layer "B.SilkS")
		)
		(fp_line
			(start -0.7874 -0.4064)
			(end -0.7874 0.4064)
			(stroke
				(width 0.1524)
				(type default)
			)
			(layer "B.SilkS")
		)
		(fp_line
			(start 0.7874 -0.4064)
			(end -0.7874 -0.4064)
			(stroke
				(width 0.1524)
				(type default)
			)
			(layer "B.SilkS")
		)
		(fp_line
			(start -0.67945 0.3048)
			(end -0.120396 0.3048)
			(stroke
				(width 0.1)
				(type default)
			)
			(layer "B.Fab")
		)
		(fp_line
			(start -0.120396 0.3048)
			(end -0.120396 0.2794)
			(stroke
				(width 0.1)
				(type default)
			)
			(layer "B.Fab")
		)
		(fp_line
			(start 0.12065 0.3048)
			(end 0.67945 0.3048)
			(stroke
				(width 0.1)
				(type default)
			)
			(layer "B.Fab")
		)
		(fp_line
			(start 0.67945 0.3048)
			(end 0.67945 -0.305054)
			(stroke
				(width 0.1)
				(type default)
			)
			(layer "B.Fab")
		)
		(fp_line
			(start -0.120396 0.2794)
			(end 0.12065 0.2794)
			(stroke
				(width 0.1)
				(type default)
			)
			(layer "B.Fab")
		)
		(fp_line
			(start 0.12065 0.2794)
			(end 0.12065 0.3048)
			(stroke
				(width 0.1)
				(type default)
			)
			(layer "B.Fab")
		)
		(fp_line
			(start -0.12065 -0.2794)
			(end -0.12065 -0.3048)
			(stroke
				(width 0.1)
				(type default)
			)
			(layer "B.Fab")
		)
		(fp_line
			(start 0.12065 -0.2794)
			(end -0.12065 -0.2794)
			(stroke
				(width 0.1)
				(type default)
			)
			(layer "B.Fab")
		)
		(fp_line
			(start -0.67945 -0.3048)
			(end -0.67945 0.3048)
			(stroke
				(width 0.1)
				(type default)
			)
			(layer "B.Fab")
		)
		(fp_line
			(start -0.12065 -0.3048)
			(end -0.67945 -0.3048)
			(stroke
				(width 0.1)
				(type default)
			)
			(layer "B.Fab")
		)
		(fp_line
			(start 0.12065 -0.305054)
			(end 0.12065 -0.2794)
			(stroke
				(width 0.1)
				(type default)
			)
			(layer "B.Fab")
		)
		(fp_line
			(start 0.67945 -0.305054)
			(end 0.12065 -0.305054)
			(stroke
				(width 0.1)
				(type default)
			)
			(layer "B.Fab")
		)
		(pad "1" smd circle
			(at 0.40005 0 90)
			(size 0 0)
			(layers "B.Cu" "B.Mask" "B.Paste")
			(net "PVDDCR_CPU1_P0")
		)
		(pad "2" smd circle
			(at -0.40005 0 90)
			(size 0 0)
			(layers "B.Cu" "B.Mask" "B.Paste")
			(net "GND")
		)
	)
)
